(kicad_pcb
	(version 20260206)
	(generator "pcbnew")
	(generator_version "10.0")
	(general
		(thickness 1.6)
		(legacy_teardrops no)
	)
	(paper "A4")
	(title_block
		(title "04192023_DAF0TMB3IC0_F0TG_MB_C_brd_V02_OCP.brd")
		(comment 1 "Grand Teton / footprints 3016-3020 of 8354")
	)
	(layers
		(0 "F.Cu" signal "TOP")
		(4 "In1.Cu" signal "GND")
		(6 "In2.Cu" signal "IN1")
		(8 "In3.Cu" signal "GND1")
		(10 "In4.Cu" signal "IN2")
		(12 "In5.Cu" signal "GND2")
		(14 "In6.Cu" signal "IN3")
		(16 "In7.Cu" signal "GND3")
		(18 "In8.Cu" signal "VCC")
		(20 "In9.Cu" signal "VCC1")
		(22 "In10.Cu" signal "GND4")
		(24 "In11.Cu" signal "IN4")
		(26 "In12.Cu" signal "GND5")
		(28 "In13.Cu" signal "IN5")
		(30 "In14.Cu" signal "GND6")
		(32 "In15.Cu" signal "IN6")
		(34 "In16.Cu" signal "GND7")
		(2 "B.Cu" signal "BOTTOM")
		(9 "F.Adhes" user "F.Adhesive")
		(11 "B.Adhes" user "B.Adhesive")
		(13 "F.Paste" user "Package Geometry/Pastemask Top")
		(15 "B.Paste" user "Package Geometry/Pastemask Bottom")
		(5 "F.SilkS" user "Ref Des/Silkscreen Top")
		(7 "B.SilkS" user "Ref Des/Silkscreen Bottom")
		(1 "F.Mask" user "Board Geometry/Soldermask Top")
		(3 "B.Mask" user "Board Geometry/Soldermask Bottom")
		(17 "Dwgs.User" user "User.Drawings")
		(19 "Cmts.User" user "User.Comments")
		(21 "Eco1.User" user "User.Eco1")
		(23 "Eco2.User" user "User.Eco2")
		(25 "Edge.Cuts" user "Board Geometry/Outline")
		(27 "Margin" user)
		(31 "F.CrtYd" user "Package Geometry/Place Bound Top")
		(29 "B.CrtYd" user "Package Geometry/Place Bound Bottom")
		(35 "F.Fab" user "Ref Des/Assembly Top")
		(33 "B.Fab" user "Ref Des/Assembly Bottom")
	)
	(footprint ""
		(layer "F.Cu")
		(at 201.352912 -96.822768)
		(property "Reference" "U28"
			(at -2.032 -2.377948 0)
			(unlocked yes)
			(layer "F.SilkS")
			(effects
				(font
					(size 0.7874 0.5842)
					(thickness 0.1524)
				)
				(justify left)
			)
		)
		(property "Value" ""
			(at 0 0 0)
			(layer "F.Fab")
			(effects
				(font
					(size 1.27 1.27)
				)
			)
		)
		(duplicate_pad_numbers_are_jumpers no)
		(fp_line
			(start -2.0574 -1.651)
			(end -0.381 -1.651)
			(stroke
				(width 0.1524)
				(type default)
			)
			(layer "F.SilkS")
		)
		(fp_line
			(start -2.0574 1.651)
			(end -2.0574 -1.651)
			(stroke
				(width 0.1524)
				(type default)
			)
			(layer "F.SilkS")
		)
		(fp_line
			(start -0.381 -1.651)
			(end 0 -1.016)
			(stroke
				(width 0.1524)
				(type default)
			)
			(layer "F.SilkS")
		)
		(fp_line
			(start 0 -1.016)
			(end 0.381 -1.651)
			(stroke
				(width 0.1524)
				(type default)
			)
			(layer "F.SilkS")
		)
		(fp_line
			(start 0.381 -1.651)
			(end 2.0574 -1.651)
			(stroke
				(width 0.1524)
				(type default)
			)
			(layer "F.SilkS")
		)
		(fp_line
			(start 2.0574 -1.651)
			(end 2.0574 1.651)
			(stroke
				(width 0.1524)
				(type default)
			)
			(layer "F.SilkS")
		)
		(fp_line
			(start 2.0574 1.651)
			(end -2.0574 1.651)
			(stroke
				(width 0.1524)
				(type default)
			)
			(layer "F.SilkS")
		)
		(fp_poly
			(pts
				(xy -2.71272 -0.719328) (xy -2.71272 -1.344168) (xy -2.159 -1.016)
			)
			(stroke
				(width 0)
				(type default)
			)
			(fill yes)
			(layer "F.SilkS")
		)
		(fp_line
			(start -1.599946 -1.199896)
			(end -0.899922 -1.199896)
			(stroke
				(width 0.1)
				(type default)
			)
			(layer "F.Fab")
		)
		(fp_line
			(start -1.599946 1.199896)
			(end -1.599946 -1.199896)
			(stroke
				(width 0.1)
				(type default)
			)
			(layer "F.Fab")
		)
		(fp_line
			(start -0.899922 -1.549908)
			(end 0.899922 -1.549908)
			(stroke
				(width 0.1)
				(type default)
			)
			(layer "F.Fab")
		)
		(fp_line
			(start -0.899922 -1.199896)
			(end -0.899922 -1.549908)
			(stroke
				(width 0.1)
				(type default)
			)
			(layer "F.Fab")
		)
		(fp_line
			(start -0.899922 1.199896)
			(end -1.599946 1.199896)
			(stroke
				(width 0.1)
				(type default)
			)
			(layer "F.Fab")
		)
		(fp_line
			(start -0.899922 1.549908)
			(end -0.899922 1.199896)
			(stroke
				(width 0.1)
				(type default)
			)
			(layer "F.Fab")
		)
		(fp_line
			(start 0.899922 -1.549908)
			(end 0.899922 -1.199896)
			(stroke
				(width 0.1)
				(type default)
			)
			(layer "F.Fab")
		)
		(fp_line
			(start 0.899922 -1.199896)
			(end 1.599946 -1.199896)
			(stroke
				(width 0.1)
				(type default)
			)
			(layer "F.Fab")
		)
		(fp_line
			(start 0.899922 1.199896)
			(end 0.899922 1.549908)
			(stroke
				(width 0.1)
				(type default)
			)
			(layer "F.Fab")
		)
		(fp_line
			(start 0.899922 1.549908)
			(end -0.899922 1.549908)
			(stroke
				(width 0.1)
				(type default)
			)
			(layer "F.Fab")
		)
		(fp_line
			(start 1.599946 -1.199896)
			(end 1.599946 1.199896)
			(stroke
				(width 0.1)
				(type default)
			)
			(layer "F.Fab")
		)
		(fp_line
			(start 1.599946 1.199896)
			(end 0.899922 1.199896)
			(stroke
				(width 0.1)
				(type default)
			)
			(layer "F.Fab")
		)
		(fp_poly
			(pts
				(xy -2.71272 -0.719328) (xy -2.71272 -1.344168) (xy -2.159 -1.016)
			)
			(stroke
				(width 0)
				(type default)
			)
			(fill yes)
			(layer "F.Fab")
		)
		(pad "1" smd rect
			(at -1.225042 -0.94996 270)
			(size 0.5588 1.3462)
			(layers "F.Cu" "F.Mask" "F.Paste")
			(net "Net_10855")
		)
		(pad "2" smd rect
			(at -1.225042 0 270)
			(size 0.5588 1.3462)
			(layers "F.Cu" "F.Mask" "F.Paste")
			(net "HP_LVC3_OCP_V3_1_P12V_R_PWRGD")
		)
		(pad "3" smd rect
			(at -1.225042 0.94996 270)
			(size 0.5588 1.3462)
			(layers "F.Cu" "F.Mask" "F.Paste")
			(net "GND")
		)
		(pad "4" smd rect
			(at 1.225042 0.94996 270)
			(size 0.5588 1.3462)
			(layers "F.Cu" "F.Mask" "F.Paste")
			(net "P12V_OCP_V3_1_PLD_R_PWRGD")
		)
		(pad "5" smd rect
			(at 1.225042 -0.94996 270)
			(size 0.5588 1.3462)
			(layers "F.Cu" "F.Mask" "F.Paste")
			(net "P3V3_AUX")
		)
	)
	(footprint ""
		(layer "F.Cu")
		(at 64.889126 -20.04822 180)
		(property "Reference" "PC2143"
			(at 0 0 180)
			(layer "F.SilkS")
			(hide yes)
			(effects
				(font
					(size 1.27 1.27)
				)
			)
		)
		(property "Value" ""
			(at 0 0 180)
			(layer "F.Fab")
			(effects
				(font
					(size 1.27 1.27)
				)
			)
		)
		(duplicate_pad_numbers_are_jumpers no)
		(fp_line
			(start 1.524 0.762)
			(end -1.524 0.762)
			(stroke
				(width 0.1524)
				(type default)
			)
			(layer "F.SilkS")
		)
		(fp_line
			(start 1.524 -0.762)
			(end 1.524 0.762)
			(stroke
				(width 0.1524)
				(type default)
			)
			(layer "F.SilkS")
		)
		(fp_line
			(start -1.524 0.762)
			(end -1.524 -0.762)
			(stroke
				(width 0.1524)
				(type default)
			)
			(layer "F.SilkS")
		)
		(fp_line
			(start -1.524 -0.762)
			(end 1.524 -0.762)
			(stroke
				(width 0.1524)
				(type default)
			)
			(layer "F.SilkS")
		)
		(fp_line
			(start 1.1049 0.724916)
			(end 1.1049 -0.724916)
			(stroke
				(width 0.1)
				(type default)
			)
			(layer "F.Fab")
		)
		(fp_line
			(start 1.1049 -0.724916)
			(end -1.1049 -0.724916)
			(stroke
				(width 0.1)
				(type default)
			)
			(layer "F.Fab")
		)
		(fp_line
			(start -1.1049 0.724916)
			(end 1.1049 0.724916)
			(stroke
				(width 0.1)
				(type default)
			)
			(layer "F.Fab")
		)
		(fp_line
			(start -1.1049 -0.724916)
			(end -1.1049 0.724916)
			(stroke
				(width 0.1)
				(type default)
			)
			(layer "F.Fab")
		)
		(pad "1" smd rect
			(at -0.889 0)
			(size 1.016 1.27)
			(layers "F.Cu" "F.Mask" "F.Paste")
			(net "P12V_OCP_V3_2")
		)
		(pad "2" smd rect
			(at 0.889 0)
			(size 1.016 1.27)
			(layers "F.Cu" "F.Mask" "F.Paste")
			(net "GND")
		)
	)
	(footprint ""
		(layer "F.Cu")
		(at 101.948234 -140.18641)
		(property "Reference" "PR602"
			(at 0 0 0)
			(layer "F.SilkS")
			(hide yes)
			(effects
				(font
					(size 1.27 1.27)
				)
			)
		)
		(property "Value" ""
			(at 0 0 0)
			(layer "F.Fab")
			(effects
				(font
					(size 1.27 1.27)
				)
			)
		)
		(duplicate_pad_numbers_are_jumpers no)
		(fp_line
			(start -0.7874 -0.4064)
			(end 0.7874 -0.4064)
			(stroke
				(width 0.1524)
				(type default)
			)
			(layer "F.SilkS")
		)
		(fp_line
			(start -0.7874 0.4064)
			(end -0.7874 -0.4064)
			(stroke
				(width 0.1524)
				(type default)
			)
			(layer "F.SilkS")
		)
		(fp_line
			(start 0.7874 -0.4064)
			(end 0.7874 0.4064)
			(stroke
				(width 0.1524)
				(type default)
			)
			(layer "F.SilkS")
		)
		(fp_line
			(start 0.7874 0.4064)
			(end -0.7874 0.4064)
			(stroke
				(width 0.1524)
				(type default)
			)
			(layer "F.SilkS")
		)
		(fp_line
			(start -0.67945 -0.305054)
			(end -0.12065 -0.305054)
			(stroke
				(width 0.1)
				(type default)
			)
			(layer "F.Fab")
		)
		(fp_line
			(start -0.67945 0.3048)
			(end -0.67945 -0.305054)
			(stroke
				(width 0.1)
				(type default)
			)
			(layer "F.Fab")
		)
		(fp_line
			(start -0.12065 -0.305054)
			(end -0.12065 -0.2794)
			(stroke
				(width 0.1)
				(type default)
			)
			(layer "F.Fab")
		)
		(fp_line
			(start -0.12065 -0.2794)
			(end 0.12065 -0.2794)
			(stroke
				(width 0.1)
				(type default)
			)
			(layer "F.Fab")
		)
		(fp_line
			(start -0.12065 0.2794)
			(end -0.12065 0.3048)
			(stroke
				(width 0.1)
				(type default)
			)
			(layer "F.Fab")
		)
		(fp_line
			(start -0.12065 0.3048)
			(end -0.67945 0.3048)
			(stroke
				(width 0.1)
				(type default)
			)
			(layer "F.Fab")
		)
		(fp_line
			(start 0.120396 0.2794)
			(end -0.12065 0.2794)
			(stroke
				(width 0.1)
				(type default)
			)
			(layer "F.Fab")
		)
		(fp_line
			(start 0.120396 0.3048)
			(end 0.120396 0.2794)
			(stroke
				(width 0.1)
				(type default)
			)
			(layer "F.Fab")
		)
		(fp_line
			(start 0.12065 -0.3048)
			(end 0.67945 -0.3048)
			(stroke
				(width 0.1)
				(type default)
			)
			(layer "F.Fab")
		)
		(fp_line
			(start 0.12065 -0.2794)
			(end 0.12065 -0.3048)
			(stroke
				(width 0.1)
				(type default)
			)
			(layer "F.Fab")
		)
		(fp_line
			(start 0.67945 -0.3048)
			(end 0.67945 0.3048)
			(stroke
				(width 0.1)
				(type default)
			)
			(layer "F.Fab")
		)
		(fp_line
			(start 0.67945 0.3048)
			(end 0.120396 0.3048)
			(stroke
				(width 0.1)
				(type default)
			)
			(layer "F.Fab")
		)
		(pad "1" smd circle
			(at -0.40005 0)
			(size 0 0)
			(layers "F.Cu" "F.Mask" "F.Paste")
			(net "PVDDCR_CPU0_P1_VINSEN")
		)
		(pad "2" smd circle
			(at 0.40005 0)
			(size 0 0)
			(layers "F.Cu" "F.Mask" "F.Paste")
			(net "GND")
		)
	)
	(footprint ""
		(layer "F.Cu")
		(at 321.107308 -101.37775 180)
		(property "Reference" "R1269"
			(at 0 0 180)
			(layer "F.SilkS")
			(hide yes)
			(effects
				(font
					(size 1.27 1.27)
				)
			)
		)
		(property "Value" ""
			(at 0 0 180)
			(layer "F.Fab")
			(effects
				(font
					(size 1.27 1.27)
				)
			)
		)
		(duplicate_pad_numbers_are_jumpers no)
		(fp_line
			(start 0.7874 0.4064)
			(end -0.7874 0.4064)
			(stroke
				(width 0.1524)
				(type default)
			)
			(layer "F.SilkS")
		)
		(fp_line
			(start 0.7874 -0.4064)
			(end 0.7874 0.4064)
			(stroke
				(width 0.1524)
				(type default)
			)
			(layer "F.SilkS")
		)
		(fp_line
			(start -0.7874 0.4064)
			(end -0.7874 -0.4064)
			(stroke
				(width 0.1524)
				(type default)
			)
			(layer "F.SilkS")
		)
		(fp_line
			(start -0.7874 -0.4064)
			(end 0.7874 -0.4064)
			(stroke
				(width 0.1524)
				(type default)
			)
			(layer "F.SilkS")
		)
		(fp_line
			(start 0.67945 0.3048)
			(end 0.120396 0.3048)
			(stroke
				(width 0.1)
				(type default)
			)
			(layer "F.Fab")
		)
		(fp_line
			(start 0.67945 -0.3048)
			(end 0.67945 0.3048)
			(stroke
				(width 0.1)
				(type default)
			)
			(layer "F.Fab")
		)
		(fp_line
			(start 0.12065 -0.2794)
			(end 0.12065 -0.3048)
			(stroke
				(width 0.1)
				(type default)
			)
			(layer "F.Fab")
		)
		(fp_line
			(start 0.12065 -0.3048)
			(end 0.67945 -0.3048)
			(stroke
				(width 0.1)
				(type default)
			)
			(layer "F.Fab")
		)
		(fp_line
			(start 0.120396 0.3048)
			(end 0.120396 0.2794)
			(stroke
				(width 0.1)
				(type default)
			)
			(layer "F.Fab")
		)
		(fp_line
			(start 0.120396 0.2794)
			(end -0.12065 0.2794)
			(stroke
				(width 0.1)
				(type default)
			)
			(layer "F.Fab")
		)
		(fp_line
			(start -0.12065 0.3048)
			(end -0.67945 0.3048)
			(stroke
				(width 0.1)
				(type default)
			)
			(layer "F.Fab")
		)
		(fp_line
			(start -0.12065 0.2794)
			(end -0.12065 0.3048)
			(stroke
				(width 0.1)
				(type default)
			)
			(layer "F.Fab")
		)
		(fp_line
			(start -0.12065 -0.2794)
			(end 0.12065 -0.2794)
			(stroke
				(width 0.1)
				(type default)
			)
			(layer "F.Fab")
		)
		(fp_line
			(start -0.12065 -0.305054)
			(end -0.12065 -0.2794)
			(stroke
				(width 0.1)
				(type default)
			)
			(layer "F.Fab")
		)
		(fp_line
			(start -0.67945 0.3048)
			(end -0.67945 -0.305054)
			(stroke
				(width 0.1)
				(type default)
			)
			(layer "F.Fab")
		)
		(fp_line
			(start -0.67945 -0.305054)
			(end -0.12065 -0.305054)
			(stroke
				(width 0.1)
				(type default)
			)
			(layer "F.Fab")
		)
		(pad "1" smd circle
			(at -0.40005 0 180)
			(size 0 0)
			(layers "F.Cu" "F.Mask" "F.Paste")
			(net "P12V_E1S_0_ADC_ALERT_R")
		)
		(pad "2" smd circle
			(at 0.40005 0 180)
			(size 0 0)
			(layers "F.Cu" "F.Mask" "F.Paste")
			(net "E1S_0_P3V3_P12V_ADC_R_ALERT")
		)
	)
	(footprint ""
		(layer "F.Cu")
		(at 431.828956 -105.32745 -90)
		(property "Reference" "PU202"
			(at 1.905 3.718306 90)
			(unlocked yes)
			(layer "F.SilkS")
			(effects
				(font
					(size 0.7874 0.5842)
					(thickness 0.1524)
				)
				(justify left)
			)
		)
		(property "Value" ""
			(at 0 0 270)
			(layer "F.Fab")
			(effects
				(font
					(size 1.27 1.27)
				)
			)
		)
		(duplicate_pad_numbers_are_jumpers no)
		(fp_line
			(start -1.774952 1.039876)
			(end 1.774952 1.039876)
			(stroke
				(width 0.1524)
				(type default)
			)
			(layer "F.SilkS")
		)
		(fp_line
			(start 1.774952 1.039876)
			(end 1.774952 -1.039876)
			(stroke
				(width 0.1524)
				(type default)
			)
			(layer "F.SilkS")
		)
		(fp_line
			(start -1.774952 -1.039876)
			(end -1.774952 1.039876)
			(stroke
				(width 0.1524)
				(type default)
			)
			(layer "F.SilkS")
		)
		(fp_line
			(start 1.774952 -1.039876)
			(end -1.774952 -1.039876)
			(stroke
				(width 0.1524)
				(type default)
			)
			(layer "F.SilkS")
		)
		(fp_poly
			(pts
				(xy -0.999998 -1.801876) (xy -0.999998 -1.039876) (xy -1.769872 -1.039876) (xy -1.769872 -0.249936)
				(xy -2.531872 -0.249936) (xy -2.531872 -1.801876)
			)
			(stroke
				(width 0)
				(type default)
			)
			(fill yes)
			(layer "F.SilkS")
		)
		(fp_line
			(start -1.769872 1.039876)
			(end 1.769872 1.039876)
			(stroke
				(width 0.1)
				(type default)
			)
			(layer "F.Fab")
		)
		(fp_line
			(start 1.769872 1.039876)
			(end 1.769872 -1.039876)
			(stroke
				(width 0.1)
				(type default)
			)
			(layer "F.Fab")
		)
		(fp_line
			(start -1.769872 -1.039876)
			(end -1.769872 1.039876)
			(stroke
				(width 0.1)
				(type default)
			)
			(layer "F.Fab")
		)
		(fp_line
			(start 1.769872 -1.039876)
			(end -1.769872 -1.039876)
			(stroke
				(width 0.1)
				(type default)
			)
			(layer "F.Fab")
		)
		(fp_poly
			(pts
				(xy -1.769872 -1.039876) (xy -0.999998 -1.039876) (xy -0.999998 -1.801876) (xy -2.531872 -1.801876)
				(xy -2.531872 -0.249936) (xy -1.769872 -0.249936)
			)
			(stroke
				(width 0)
				(type default)
			)
			(fill yes)
			(layer "F.Fab")
		)
		(pad "A1" smd circle
			(at -1.500124 -0.750062 270)
			(size 0.2286 0.2286)
			(layers "F.Cu" "F.Mask" "F.Paste")
			(net "P3V3_OCP_SENSE_1")
		)
		(pad "A2" smd circle
			(at -0.999998 -0.750062 270)
			(size 0.2286 0.2286)
			(layers "F.Cu" "F.Mask" "F.Paste")
			(net "P3V3_OCP_VCC_1")
		)
		(pad "A3" smd circle
			(at -0.499872 -0.750062 270)
			(size 0.2286 0.2286)
			(layers "F.Cu" "F.Mask" "F.Paste")
			(net "P3V3_AUX")
		)
		(pad "A4" smd circle
			(at 0 -0.750062 270)
			(size 0.2286 0.2286)
			(layers "F.Cu" "F.Mask" "F.Paste")
			(net "P3V3_OCP_SFF_R")
		)
		(pad "A5" smd circle
			(at 0.499872 -0.750062 270)
			(size 0.2286 0.2286)
			(layers "F.Cu" "F.Mask" "F.Paste")
			(net "P3V3_AUX")
		)
		(pad "A6" smd circle
			(at 0.999998 -0.750062 270)
			(size 0.2286 0.2286)
			(layers "F.Cu" "F.Mask" "F.Paste")
			(net "P3V3_OCP_GATE_PU202_1")
		)
		(pad "A7" smd circle
			(at 1.500124 -0.750062 270)
			(size 0.2286 0.2286)
			(layers "F.Cu" "F.Mask" "F.Paste")
			(net "GND")
		)
		(pad "B1" smd circle
			(at -1.500124 -0.249936 270)
			(size 0.2286 0.2286)
			(layers "F.Cu" "F.Mask" "F.Paste")
			(net "P3V3_OCP_CB_1")
		)
		(pad "B2" smd circle
			(at -0.999998 -0.249936 270)
			(size 0.2286 0.2286)
			(layers "F.Cu" "F.Mask" "F.Paste")
			(net "GND")
		)
		(pad "B3" smd circle
			(at -0.499872 -0.249936 270)
			(size 0.2286 0.2286)
			(layers "F.Cu" "F.Mask" "F.Paste")
			(net "P3V3_AUX")
		)
		(pad "B4" smd circle
			(at 0 -0.249936 270)
			(size 0.2286 0.2286)
			(layers "F.Cu" "F.Mask" "F.Paste")
			(net "P3V3_OCP_SFF_R")
		)
		(pad "B5" smd circle
			(at 0.499872 -0.249936 270)
			(size 0.2286 0.2286)
			(layers "F.Cu" "F.Mask" "F.Paste")
			(net "P3V3_AUX")
		)
		(pad "B6" smd circle
			(at 0.999998 -0.249936 270)
			(size 0.2286 0.2286)
			(layers "F.Cu" "F.Mask" "F.Paste")
			(net "P3V3_OCP_SFF_R")
		)
		(pad "B7" smd circle
			(at 1.500124 -0.249936 270)
			(size 0.2286 0.2286)
			(layers "F.Cu" "F.Mask" "F.Paste")
			(net "GND")
		)
		(pad "C1" smd circle
			(at -1.500124 0.249936 270)
			(size 0.2286 0.2286)
			(layers "F.Cu" "F.Mask" "F.Paste")
			(net "GND")
		)
		(pad "C2" smd circle
			(at -0.999998 0.249936 270)
			(size 0.2286 0.2286)
			(layers "F.Cu" "F.Mask" "F.Paste")
			(net "GND")
		)
		(pad "C3" smd circle
			(at -0.499872 0.249936 270)
			(size 0.2286 0.2286)
			(layers "F.Cu" "F.Mask" "F.Paste")
			(net "P3V3_AUX")
		)
		(pad "C4" smd circle
			(at 0 0.249936 270)
			(size 0.2286 0.2286)
			(layers "F.Cu" "F.Mask" "F.Paste")
			(net "P3V3_OCP_SFF_R")
		)
		(pad "C5" smd circle
			(at 0.499872 0.249936 270)
			(size 0.2286 0.2286)
			(layers "F.Cu" "F.Mask" "F.Paste")
			(net "P3V3_AUX")
		)
		(pad "C6" smd circle
			(at 0.999998 0.249936 270)
			(size 0.2286 0.2286)
			(layers "F.Cu" "F.Mask" "F.Paste")
			(net "P3V3_OCP_SFF_R")
		)
		(pad "C7" smd circle
			(at 1.500124 0.249936 270)
			(size 0.2286 0.2286)
			(layers "F.Cu" "F.Mask" "F.Paste")
			(net "P3V3_OCP_FAULT_1")
		)
		(pad "D1" smd circle
			(at -1.500124 0.750062 270)
			(size 0.2286 0.2286)
			(layers "F.Cu" "F.Mask" "F.Paste")
			(net "P3V3_OCP_REG_1")
		)
		(pad "D2" smd circle
			(at -0.999998 0.750062 270)
			(size 0.2286 0.2286)
			(layers "F.Cu" "F.Mask" "F.Paste")
			(net "P3V3_OCP_UV_1")
		)
		(pad "D3" smd circle
			(at -0.499872 0.750062 270)
			(size 0.2286 0.2286)
			(layers "F.Cu" "F.Mask" "F.Paste")
			(net "P3V3_OCP_OV_1")
		)
		(pad "D4" smd circle
			(at 0 0.750062 270)
			(size 0.2286 0.2286)
			(layers "F.Cu" "F.Mask" "F.Paste")
			(net "P3V3_OCP_SFF_R")
		)
		(pad "D5" smd circle
			(at 0.499872 0.750062 270)
			(size 0.2286 0.2286)
			(layers "F.Cu" "F.Mask" "F.Paste")
			(net "P3V3_AUX")
		)
		(pad "D6" smd circle
			(at 0.999998 0.750062 270)
			(size 0.2286 0.2286)
			(layers "F.Cu" "F.Mask" "F.Paste")
			(net "P3V3_OCP_SFF_R")
		)
		(pad "D7" smd circle
			(at 1.500124 0.750062 270)
			(size 0.2286 0.2286)
			(layers "F.Cu" "F.Mask" "F.Paste")
			(net "P3V3_OCP_PWRGD_1")
		)
	)
)
